FILE_TYPE = MACRO_DRAWING;
SET COLOR_WIRE YELLOW;
SET COLOR_PROP ORANGE;
SET COLOR_DOT WHITE;
SET COLOR_ARC YELLOW;
SET COLOR_BODY GREEN;
SET COLOR_NOTE PURPLE;
SET PROP_DISPLAY VALUE;
SET PAGE_NUMBER P117;
FORCEADD QUANTA_TITLE_BLOCK_C..1
(0 0);
FORCEPROP 1 LAST CUSTOM_TXT_CDS <NAME_2>
J 0
(-3175 50);
FORCEPROP 1 LAST CUSTOM_TXT_CDS <NAME_1>
J 0
(-3175 175);
FORCEPROP 1 LAST CUSTOM_TXT_CDS <Q_NUMBER>
J 0
(-1403 103);
DISPLAY 1.212766 (-1403 103);
FORCEPROP 1 LAST CUSTOM_TXT_CDS <Q_PROJ>
J 0
(-2382 102);
DISPLAY 1.212766 (-2382 102);
FORCEPROP 1 LAST CUSTOM_TXT_CDS <Q_REV>
J 0
(-184 103);
DISPLAY 1.212766 (-184 103);
FORCEPROP 1 LAST CUSTOM_TXT_CDS <CON_LAST_MODIFIED>
J 0
(-1885 15);
DISPLAY 0.978723 (-1885 15);
FORCEPROP 1 LAST CUSTOM_TXT_CDS <CON_PAGE_NUM> OF <CON_TOTAL_PAGES>
J 0
(-446 18);
DISPLAY 0.978723 (-446 18);
FORCEPROP 1 LAST Q_DEPT BU9
J 1
(-3763 49);
DISPLAY 1.957447 (-3763 49);
PAINT GREEN (-3763 49);
FORCEPROP 1 LAST Q_TITLE SCM CONN
J 0
(-9250 75);
DISPLAY 2.446809 (-9250 75);
PAINT GREEN (-9250 75);
FORCEPROP 2 LAST PAGE_BORDER TRUE
J 0
(-7890 5250);
DISPLAY 0.638298 (-7890 5250);
PAINT PINK (-7890 5250);
DISPLAY INVISIBLE (-7890 5250);
FORCEPROP 2 LAST CDS_LIB pure_quanta
J 0
(0 0);
DISPLAY INVISIBLE (0 0);
FORCEPROP 1 LAST CDS_LMAN_SYM_OUTLINE -9475,6775,100,-125
J 0
(0 0);
DISPLAY 0.468085 (0 0);
PAINT GREEN (0 0);
DISPLAY INVISIBLE (0 0);
FORCEPROP 1 LAST COMMENT_BODY TRUE
J 0
(12 -13);
DISPLAY 0.978723 (12 -13);
PAINT GREEN (12 -13);
DISPLAY INVISIBLE (12 -13);
FORCEPROP 2 LAST CDS_XR_PAGE_TITLE CR-117 : @T6G_MB_LIB.T6G(SCH_1):PAGE117
J 0
(-7890 5250);
DISPLAY 0.638298 (-7890 5250);
PAINT PINK (-7890 5250);
DISPLAY INVISIBLE (-7890 5250);
FORCEPROP 2 LAST CUSTOM_TXT_CDS <XR_PAGE_TITLE>
J 0
(-7890 5250);
DISPLAY 0.638298 (-7890 5250);
PAINT PINK (-7890 5250);
DISPLAY INVISIBLE (-7890 5250);
FORCEPROP 0 LAST CDS_CON_LAST_MODIFIED Wed Mar 09 17:44:52 2022
J 0
(-1885 15);
DISPLAY INVISIBLE (-1885 15);
QUIT
